# BASEBOARD_FAB2 (Tioga Pass) — schematic netlist excerpt (pin names and nets, part order shuffled) for the footprints in the layout excerpt that follows; sources: Cadence DE-HDL packaged netlist, KiCad conversion of Wiwynn_Tioga_Pass_MB.brd

R1W40  RES  4.75K 1% CHIP  pkg 0402  page 188 : A = P3V3_STBY ; B = EXT_MDIO_I2C_SEL
R1M16  RES  0.0 5% CHIP  pkg 0402  page 186 : A = RMII_BMC_OCP_RXD1 ; B = RMII_BMC_OCP_RXD1_R
C2R12  CAP_A  1.0UF 6.3V 10% X6S  pkg 0402V  page 157 : A = FP_NMI_BTN_OUT_N ; B = GND

(kicad_pcb
	(version 20260206)
	(generator "pcbnew")
	(generator_version "10.0")
	(general
		(thickness 1.6)
		(legacy_teardrops no)
	)
	(paper "A4")
	(title_block
		(title "Wiwynn_Tioga_Pass_MB.brd")
		(comment 1 "Tioga Pass / footprints 2393-2395 of 4770")
	)
	(layers
		(0 "F.Cu" signal "TOP")
		(4 "In1.Cu" signal "L2GND")
		(6 "In2.Cu" signal "L3")
		(8 "In3.Cu" signal "L4GND")
		(10 "In4.Cu" signal "L5")
		(12 "In5.Cu" signal "L6GND")
		(14 "In6.Cu" signal "L7VCC")
		(16 "In7.Cu" signal "L8VCC")
		(18 "In8.Cu" signal "L9GND")
		(20 "In9.Cu" signal "L10")
		(22 "In10.Cu" signal "L11GND")
		(24 "In11.Cu" signal "L12")
		(26 "In12.Cu" signal "L13GND")
		(2 "B.Cu" signal "BOTTOM")
		(9 "F.Adhes" user "F.Adhesive")
		(11 "B.Adhes" user "B.Adhesive")
		(13 "F.Paste" user "Package Geometry/Pastemask Top")
		(15 "B.Paste" user "Package Geometry/Pastemask Bottom")
		(5 "F.SilkS" user "Ref Des/Silkscreen Top")
		(7 "B.SilkS" user "Ref Des/Silkscreen Bottom")
		(1 "F.Mask" user "Board Geometry/Soldermask Top")
		(3 "B.Mask" user "Board Geometry/Soldermask Bottom")
		(17 "Dwgs.User" user "User.Drawings")
		(19 "Cmts.User" user "User.Comments")
		(21 "Eco1.User" user "User.Eco1")
		(23 "Eco2.User" user "User.Eco2")
		(25 "Edge.Cuts" user "Board Geometry/Outline")
		(27 "Margin" user)
		(31 "F.CrtYd" user "Package Geometry/Place Bound Top")
		(29 "B.CrtYd" user "Package Geometry/Place Bound Bottom")
		(35 "F.Fab" user "Ref Des/Assembly Top")
		(33 "B.Fab" user "Ref Des/Assembly Bottom")
	)
	(footprint ""
		(layer "B.Cu")
		(at 440.67222 -58.02376 90)
		(property "Reference" "R1W40"
			(at 0.8382 -0.67818 90)
			(unlocked yes)
			(layer "B.SilkS")
			(effects
				(font
					(size 0.4064 0.254)
					(thickness 0.1524)
				)
				(justify left mirror)
			)
		)
		(property "Value" ""
			(at 0 0 90)
			(layer "B.Fab")
			(effects
				(font
					(size 1.27 1.27)
				)
				(justify mirror)
			)
		)
		(duplicate_pad_numbers_are_jumpers no)
		(fp_poly
			(pts
				(xy 0.2794 -0.1016) (xy -0.2794 -0.1016) (xy -0.2794 0.9906) (xy 0.2794 0.9906)
			)
			(stroke
				(width 0)
				(type default)
			)
			(fill no)
			(layer "B.CrtYd")
		)
		(fp_line
			(start 0.2794 -0.1016)
			(end 0.2794 0.9906)
			(stroke
				(width 0.1)
				(type default)
			)
			(layer "B.Fab")
		)
		(fp_line
			(start -0.2794 -0.1016)
			(end 0.2794 -0.1016)
			(stroke
				(width 0.1)
				(type default)
			)
			(layer "B.Fab")
		)
		(fp_line
			(start 0.2794 0.9906)
			(end -0.2794 0.9906)
			(stroke
				(width 0.1)
				(type default)
			)
			(layer "B.Fab")
		)
		(fp_line
			(start -0.2794 0.9906)
			(end -0.2794 -0.1016)
			(stroke
				(width 0.1)
				(type default)
			)
			(layer "B.Fab")
		)
		(pad "1" smd rect
			(at 0 0 270)
			(size 0.508 0.508)
			(layers "B.Cu" "B.Mask" "B.Paste")
			(net "P3V3_STBY")
		)
		(pad "2" smd rect
			(at 0 0.889 270)
			(size 0.508 0.508)
			(layers "B.Cu" "B.Mask" "B.Paste")
			(net "EXT_MDIO_I2C_SEL")
		)
		(zone
			(layer "B.Cu")
			(hatch none 0.5)
			(connect_pads
				(clearance 0)
			)
			(min_thickness 0.25)
			(keepout
				(tracks allowed)
				(vias not_allowed)
				(pads allowed)
				(copperpour not_allowed)
				(footprints allowed)
			)
			(placement
				(enabled no)
				(sheetname "")
			)
			(fill
				(thermal_gap 0.5)
				(thermal_bridge_width 0.5)
				(island_removal_mode 0)
			)
			(polygon
				(pts
					(xy 440.92622 -58.27776) (xy 440.92622 -57.76976) (xy 441.30722 -57.76976) (xy 441.30722 -58.27776)
				)
			)
		)
		(zone
			(layer "B.Cu")
			(hatch none 0.5)
			(connect_pads
				(clearance 0)
			)
			(min_thickness 0.25)
			(keepout
				(tracks not_allowed)
				(vias allowed)
				(pads allowed)
				(copperpour not_allowed)
				(footprints allowed)
			)
			(placement
				(enabled no)
				(sheetname "")
			)
			(fill
				(thermal_gap 0.5)
				(thermal_bridge_width 0.5)
				(island_removal_mode 0)
			)
			(polygon
				(pts
					(xy 441.30722 -58.27776) (xy 441.30722 -57.76976) (xy 440.92622 -57.76976) (xy 440.92622 -58.27776)
				)
			)
		)
	)
	(footprint ""
		(layer "B.Cu")
		(at 470.662 -116.84 180)
		(property "Reference" "R1M16"
			(at 0 0 0)
			(layer "B.SilkS")
			(hide yes)
			(effects
				(font
					(size 1.27 1.27)
				)
				(justify mirror)
			)
		)
		(property "Value" ""
			(at 0 0 0)
			(layer "B.Fab")
			(effects
				(font
					(size 1.27 1.27)
				)
				(justify mirror)
			)
		)
		(duplicate_pad_numbers_are_jumpers no)
		(fp_poly
			(pts
				(xy 0.2794 -0.1016) (xy -0.2794 -0.1016) (xy -0.2794 0.9906) (xy 0.2794 0.9906)
			)
			(stroke
				(width 0)
				(type default)
			)
			(fill no)
			(layer "B.CrtYd")
		)
		(fp_line
			(start 0.2794 0.9906)
			(end -0.2794 0.9906)
			(stroke
				(width 0.1)
				(type default)
			)
			(layer "B.Fab")
		)
		(fp_line
			(start 0.2794 -0.1016)
			(end 0.2794 0.9906)
			(stroke
				(width 0.1)
				(type default)
			)
			(layer "B.Fab")
		)
		(fp_line
			(start -0.2794 0.9906)
			(end -0.2794 -0.1016)
			(stroke
				(width 0.1)
				(type default)
			)
			(layer "B.Fab")
		)
		(fp_line
			(start -0.2794 -0.1016)
			(end 0.2794 -0.1016)
			(stroke
				(width 0.1)
				(type default)
			)
			(layer "B.Fab")
		)
		(pad "1" smd rect
			(at 0 0)
			(size 0.508 0.508)
			(layers "B.Cu" "B.Mask" "B.Paste")
			(net "RMII_BMC_OCP_RXD1")
		)
		(pad "2" smd rect
			(at 0 0.889)
			(size 0.508 0.508)
			(layers "B.Cu" "B.Mask" "B.Paste")
			(net "RMII_BMC_OCP_RXD1_R")
		)
		(zone
			(layer "B.Cu")
			(hatch none 0.5)
			(connect_pads
				(clearance 0)
			)
			(min_thickness 0.25)
			(keepout
				(tracks not_allowed)
				(vias allowed)
				(pads allowed)
				(copperpour not_allowed)
				(footprints allowed)
			)
			(placement
				(enabled no)
				(sheetname "")
			)
			(fill
				(thermal_gap 0.5)
				(thermal_bridge_width 0.5)
				(island_removal_mode 0)
			)
			(polygon
				(pts
					(xy 470.408 -117.475) (xy 470.916 -117.475) (xy 470.916 -117.094) (xy 470.408 -117.094)
				)
			)
		)
		(zone
			(layer "B.Cu")
			(hatch none 0.5)
			(connect_pads
				(clearance 0)
			)
			(min_thickness 0.25)
			(keepout
				(tracks allowed)
				(vias not_allowed)
				(pads allowed)
				(copperpour not_allowed)
				(footprints allowed)
			)
			(placement
				(enabled no)
				(sheetname "")
			)
			(fill
				(thermal_gap 0.5)
				(thermal_bridge_width 0.5)
				(island_removal_mode 0)
			)
			(polygon
				(pts
					(xy 470.408 -117.094) (xy 470.916 -117.094) (xy 470.916 -117.475) (xy 470.408 -117.475)
				)
			)
		)
	)
	(footprint ""
		(layer "B.Cu")
		(at 410.097986 -11.857736 -90)
		(property "Reference" "C2R12"
			(at 0 0 90)
			(layer "B.SilkS")
			(hide yes)
			(effects
				(font
					(size 1.27 1.27)
				)
				(justify mirror)
			)
		)
		(property "Value" ""
			(at 0 0 90)
			(layer "B.Fab")
			(effects
				(font
					(size 1.27 1.27)
				)
				(justify mirror)
			)
		)
		(duplicate_pad_numbers_are_jumpers no)
		(fp_poly
			(pts
				(xy -0.3048 -0.1016) (xy -0.3048 0.9906) (xy 0.3048 0.9906) (xy 0.3048 -0.1016)
			)
			(stroke
				(width 0)
				(type default)
			)
			(fill no)
			(layer "B.CrtYd")
		)
		(fp_line
			(start -0.3048 0.9906)
			(end -0.3048 -0.1016)
			(stroke
				(width 0.1)
				(type default)
			)
			(layer "B.Fab")
		)
		(fp_line
			(start 0.3048 0.9906)
			(end -0.3048 0.9906)
			(stroke
				(width 0.1)
				(type default)
			)
			(layer "B.Fab")
		)
		(fp_line
			(start -0.3048 -0.1016)
			(end 0.3048 -0.1016)
			(stroke
				(width 0.1)
				(type default)
			)
			(layer "B.Fab")
		)
		(fp_line
			(start 0.3048 -0.1016)
			(end 0.3048 0.9906)
			(stroke
				(width 0.1)
				(type default)
			)
			(layer "B.Fab")
		)
		(pad "1" smd rect
			(at 0 0 90)
			(size 0.508 0.508)
			(layers "B.Cu" "B.Mask" "B.Paste")
			(net "FP_NMI_BTN_OUT_N")
		)
		(pad "2" smd rect
			(at 0 0.889 90)
			(size 0.508 0.508)
			(layers "B.Cu" "B.Mask" "B.Paste")
			(net "GND")
		)
		(zone
			(layer "B.Cu")
			(hatch none 0.5)
			(connect_pads
				(clearance 0)
			)
			(min_thickness 0.25)
			(keepout
				(tracks not_allowed)
				(vias allowed)
				(pads allowed)
				(copperpour not_allowed)
				(footprints allowed)
			)
			(placement
				(enabled no)
				(sheetname "")
			)
			(fill
				(thermal_gap 0.5)
				(thermal_bridge_width 0.5)
				(island_removal_mode 0)
			)
			(polygon
				(pts
					(xy 409.462986 -11.603736) (xy 409.462986 -12.111736) (xy 409.843986 -12.111736) (xy 409.843986 -11.603736)
				)
			)
		)
		(zone
			(layer "B.Cu")
			(hatch none 0.5)
			(connect_pads
				(clearance 0)
			)
			(min_thickness 0.25)
			(keepout
				(tracks allowed)
				(vias not_allowed)
				(pads allowed)
				(copperpour not_allowed)
				(footprints allowed)
			)
			(placement
				(enabled no)
				(sheetname "")
			)
			(fill
				(thermal_gap 0.5)
				(thermal_bridge_width 0.5)
				(island_removal_mode 0)
			)
			(polygon
				(pts
					(xy 409.843986 -11.603736) (xy 409.843986 -12.111736) (xy 409.462986 -12.111736) (xy 409.462986 -11.603736)
				)
			)
		)
	)
)
